# S9S_MB_2U (Grand Teton) — schematic netlist excerpt (pin names and nets, part order shuffled) for the footprints in the layout excerpt that follows; sources: Cadence DE-HDL packaged netlist, KiCad conversion of 03242023_DA0F0TMBIJ0_F0T_Motherboard_J_brd_V01_OCP.brd

C2446  Q_CAP  1000PF 50V 5% X7R  pkg 0402  page 284 : A = PVCCFA_EHV_FIVRA_CPU1_EN_R ; B = GND
R1141  Q_RES  27.4 1% CHIP  pkg 0402LF  page 155 : A = CLK_50M_NCSI_OCP_1 ; B = CLK_50M_NCSI_OCP_SFF

(kicad_pcb
	(version 20260206)
	(generator "pcbnew")
	(generator_version "10.0")
	(general
		(thickness 1.6)
		(legacy_teardrops no)
	)
	(paper "A4")
	(title_block
		(title "03242023_DA0F0TMBIJ0_F0T_Motherboard_J_brd_V01_OCP.brd")
		(comment 1 "Grand Teton / footprints 3657-3658 of 6105")
	)
	(layers
		(0 "F.Cu" signal "TOP")
		(4 "In1.Cu" signal "GND")
		(6 "In2.Cu" signal "IN1")
		(8 "In3.Cu" signal "GND1")
		(10 "In4.Cu" signal "IN2")
		(12 "In5.Cu" signal "GND2")
		(14 "In6.Cu" signal "IN3")
		(16 "In7.Cu" signal "GND3")
		(18 "In8.Cu" signal "VCC")
		(20 "In9.Cu" signal "VCC1")
		(22 "In10.Cu" signal "GND4")
		(24 "In11.Cu" signal "IN4")
		(26 "In12.Cu" signal "GND5")
		(28 "In13.Cu" signal "IN5")
		(30 "In14.Cu" signal "GND6")
		(32 "In15.Cu" signal "IN6")
		(34 "In16.Cu" signal "GND7")
		(2 "B.Cu" signal "BOTTOM")
		(9 "F.Adhes" user "F.Adhesive")
		(11 "B.Adhes" user "B.Adhesive")
		(13 "F.Paste" user "Package Geometry/Pastemask Top")
		(15 "B.Paste" user "Package Geometry/Pastemask Bottom")
		(5 "F.SilkS" user "Ref Des/Silkscreen Top")
		(7 "B.SilkS" user "Ref Des/Silkscreen Bottom")
		(1 "F.Mask" user "Board Geometry/Soldermask Top")
		(3 "B.Mask" user "Board Geometry/Soldermask Bottom")
		(17 "Dwgs.User" user "User.Drawings")
		(19 "Cmts.User" user "User.Comments")
		(21 "Eco1.User" user "User.Eco1")
		(23 "Eco2.User" user "User.Eco2")
		(25 "Edge.Cuts" user "Board Geometry/Outline")
		(27 "Margin" user)
		(31 "F.CrtYd" user "Package Geometry/Place Bound Top")
		(29 "B.CrtYd" user "Package Geometry/Place Bound Bottom")
		(35 "F.Fab" user "Ref Des/Assembly Top")
		(33 "B.Fab" user "Ref Des/Assembly Bottom")
	)
	(footprint ""
		(layer "F.Cu")
		(at 104.13492 -354.445062 -90)
		(property "Reference" "C2446"
			(at 0 0 270)
			(layer "F.SilkS")
			(hide yes)
			(effects
				(font
					(size 1.27 1.27)
				)
			)
		)
		(property "Value" ""
			(at 0 0 270)
			(layer "F.Fab")
			(effects
				(font
					(size 1.27 1.27)
				)
			)
		)
		(duplicate_pad_numbers_are_jumpers no)
		(fp_line
			(start -0.7874 0.4064)
			(end -0.7874 -0.4064)
			(stroke
				(width 0.1524)
				(type default)
			)
			(layer "F.SilkS")
		)
		(fp_line
			(start 0.7874 0.4064)
			(end -0.7874 0.4064)
			(stroke
				(width 0.1524)
				(type default)
			)
			(layer "F.SilkS")
		)
		(fp_line
			(start -0.7874 -0.4064)
			(end 0.7874 -0.4064)
			(stroke
				(width 0.1524)
				(type default)
			)
			(layer "F.SilkS")
		)
		(fp_line
			(start 0.7874 -0.4064)
			(end 0.7874 0.4064)
			(stroke
				(width 0.1524)
				(type default)
			)
			(layer "F.SilkS")
		)
		(fp_line
			(start -0.67945 0.3048)
			(end -0.67945 -0.305054)
			(stroke
				(width 0.1)
				(type default)
			)
			(layer "F.Fab")
		)
		(fp_line
			(start -0.12065 0.3048)
			(end -0.67945 0.3048)
			(stroke
				(width 0.1)
				(type default)
			)
			(layer "F.Fab")
		)
		(fp_line
			(start 0.120396 0.3048)
			(end 0.120396 0.2794)
			(stroke
				(width 0.1)
				(type default)
			)
			(layer "F.Fab")
		)
		(fp_line
			(start 0.67945 0.3048)
			(end 0.120396 0.3048)
			(stroke
				(width 0.1)
				(type default)
			)
			(layer "F.Fab")
		)
		(fp_line
			(start -0.12065 0.2794)
			(end -0.12065 0.3048)
			(stroke
				(width 0.1)
				(type default)
			)
			(layer "F.Fab")
		)
		(fp_line
			(start 0.120396 0.2794)
			(end -0.12065 0.2794)
			(stroke
				(width 0.1)
				(type default)
			)
			(layer "F.Fab")
		)
		(fp_line
			(start -0.12065 -0.2794)
			(end 0.12065 -0.2794)
			(stroke
				(width 0.1)
				(type default)
			)
			(layer "F.Fab")
		)
		(fp_line
			(start 0.12065 -0.2794)
			(end 0.12065 -0.3048)
			(stroke
				(width 0.1)
				(type default)
			)
			(layer "F.Fab")
		)
		(fp_line
			(start 0.12065 -0.3048)
			(end 0.67945 -0.3048)
			(stroke
				(width 0.1)
				(type default)
			)
			(layer "F.Fab")
		)
		(fp_line
			(start 0.67945 -0.3048)
			(end 0.67945 0.3048)
			(stroke
				(width 0.1)
				(type default)
			)
			(layer "F.Fab")
		)
		(fp_line
			(start -0.67945 -0.305054)
			(end -0.12065 -0.305054)
			(stroke
				(width 0.1)
				(type default)
			)
			(layer "F.Fab")
		)
		(fp_line
			(start -0.12065 -0.305054)
			(end -0.12065 -0.2794)
			(stroke
				(width 0.1)
				(type default)
			)
			(layer "F.Fab")
		)
		(pad "1" smd circle
			(at -0.40005 0 270)
			(size 0 0)
			(layers "F.Cu" "F.Mask" "F.Paste")
			(net "PVCCFA_EHV_FIVRA_CPU1_EN_R")
		)
		(pad "2" smd circle
			(at 0.40005 0 270)
			(size 0 0)
			(layers "F.Cu" "F.Mask" "F.Paste")
			(net "GND")
		)
	)
	(footprint ""
		(layer "F.Cu")
		(at 211.210906 -16.343122 -90)
		(property "Reference" "R1141"
			(at 0 0 270)
			(layer "F.SilkS")
			(hide yes)
			(effects
				(font
					(size 1.27 1.27)
				)
			)
		)
		(property "Value" ""
			(at 0 0 270)
			(layer "F.Fab")
			(effects
				(font
					(size 1.27 1.27)
				)
			)
		)
		(duplicate_pad_numbers_are_jumpers no)
		(fp_line
			(start -0.7874 0.4064)
			(end -0.7874 -0.4064)
			(stroke
				(width 0.1524)
				(type default)
			)
			(layer "F.SilkS")
		)
		(fp_line
			(start 0.7874 0.4064)
			(end -0.7874 0.4064)
			(stroke
				(width 0.1524)
				(type default)
			)
			(layer "F.SilkS")
		)
		(fp_line
			(start -0.7874 -0.4064)
			(end 0.7874 -0.4064)
			(stroke
				(width 0.1524)
				(type default)
			)
			(layer "F.SilkS")
		)
		(fp_line
			(start 0.7874 -0.4064)
			(end 0.7874 0.4064)
			(stroke
				(width 0.1524)
				(type default)
			)
			(layer "F.SilkS")
		)
		(fp_line
			(start -0.67945 0.3048)
			(end -0.67945 -0.305054)
			(stroke
				(width 0.1)
				(type default)
			)
			(layer "F.Fab")
		)
		(fp_line
			(start -0.12065 0.3048)
			(end -0.67945 0.3048)
			(stroke
				(width 0.1)
				(type default)
			)
			(layer "F.Fab")
		)
		(fp_line
			(start 0.120396 0.3048)
			(end 0.120396 0.2794)
			(stroke
				(width 0.1)
				(type default)
			)
			(layer "F.Fab")
		)
		(fp_line
			(start 0.67945 0.3048)
			(end 0.120396 0.3048)
			(stroke
				(width 0.1)
				(type default)
			)
			(layer "F.Fab")
		)
		(fp_line
			(start -0.12065 0.2794)
			(end -0.12065 0.3048)
			(stroke
				(width 0.1)
				(type default)
			)
			(layer "F.Fab")
		)
		(fp_line
			(start 0.120396 0.2794)
			(end -0.12065 0.2794)
			(stroke
				(width 0.1)
				(type default)
			)
			(layer "F.Fab")
		)
		(fp_line
			(start -0.12065 -0.2794)
			(end 0.12065 -0.2794)
			(stroke
				(width 0.1)
				(type default)
			)
			(layer "F.Fab")
		)
		(fp_line
			(start 0.12065 -0.2794)
			(end 0.12065 -0.3048)
			(stroke
				(width 0.1)
				(type default)
			)
			(layer "F.Fab")
		)
		(fp_line
			(start 0.12065 -0.3048)
			(end 0.67945 -0.3048)
			(stroke
				(width 0.1)
				(type default)
			)
			(layer "F.Fab")
		)
		(fp_line
			(start 0.67945 -0.3048)
			(end 0.67945 0.3048)
			(stroke
				(width 0.1)
				(type default)
			)
			(layer "F.Fab")
		)
		(fp_line
			(start -0.67945 -0.305054)
			(end -0.12065 -0.305054)
			(stroke
				(width 0.1)
				(type default)
			)
			(layer "F.Fab")
		)
		(fp_line
			(start -0.12065 -0.305054)
			(end -0.12065 -0.2794)
			(stroke
				(width 0.1)
				(type default)
			)
			(layer "F.Fab")
		)
		(pad "1" smd circle
			(at -0.40005 0 270)
			(size 0 0)
			(layers "F.Cu" "F.Mask" "F.Paste")
			(net "CLK_50M_NCSI_OCP_1")
		)
		(pad "2" smd circle
			(at 0.40005 0 270)
			(size 0 0)
			(layers "F.Cu" "F.Mask" "F.Paste")
			(net "CLK_50M_NCSI_OCP_SFF")
		)
	)
)
